(kicad_pcb
	(version 20260206)
	(generator "pcbnew")
	(generator_version "10.0")
	(general
		(thickness 1.6)
		(legacy_teardrops no)
	)
	(paper "A4")
	(title_block
		(title "12092022_DA0F0TFB6D0_F0T_FAN_BOARD_MP5048_D_brd_v02_OCP.brd")
		(comment 1 "Grand Teton / footprints 710-715 of 924")
	)
	(layers
		(0 "F.Cu" signal "TOP")
		(4 "In1.Cu" signal "GND")
		(6 "In2.Cu" signal "IN1")
		(8 "In3.Cu" signal "IN2")
		(10 "In4.Cu" signal "GND1")
		(2 "B.Cu" signal "BOTTOM")
		(9 "F.Adhes" user "F.Adhesive")
		(11 "B.Adhes" user "B.Adhesive")
		(13 "F.Paste" user "Package Geometry/Pastemask Top")
		(15 "B.Paste" user "Package Geometry/Pastemask Bottom")
		(5 "F.SilkS" user "Ref Des/Silkscreen Top")
		(7 "B.SilkS" user "Ref Des/Silkscreen Bottom")
		(1 "F.Mask" user "Board Geometry/Soldermask Top")
		(3 "B.Mask" user "Board Geometry/Soldermask Bottom")
		(17 "Dwgs.User" user "User.Drawings")
		(19 "Cmts.User" user "User.Comments")
		(21 "Eco1.User" user "User.Eco1")
		(23 "Eco2.User" user "User.Eco2")
		(25 "Edge.Cuts" user "Board Geometry/Outline")
		(27 "Margin" user)
		(31 "F.CrtYd" user "Package Geometry/Place Bound Top")
		(29 "B.CrtYd" user "Package Geometry/Place Bound Bottom")
		(35 "F.Fab" user "Ref Des/Assembly Top")
		(33 "B.Fab" user "Ref Des/Assembly Bottom")
	)
	(footprint ""
		(layer "F.Cu")
		(at 33.02 -124.206 90)
		(property "Reference" "R4778"
			(at 0 0 90)
			(layer "F.SilkS")
			(hide yes)
			(effects
				(font
					(size 1.27 1.27)
				)
			)
		)
		(property "Value" ""
			(at 0 0 90)
			(layer "F.Fab")
			(effects
				(font
					(size 1.27 1.27)
				)
			)
		)
		(duplicate_pad_numbers_are_jumpers no)
		(fp_line
			(start 0.7874 -0.4064)
			(end 0.7874 0.4064)
			(stroke
				(width 0.1524)
				(type default)
			)
			(layer "F.SilkS")
		)
		(fp_line
			(start -0.7874 -0.4064)
			(end 0.7874 -0.4064)
			(stroke
				(width 0.1524)
				(type default)
			)
			(layer "F.SilkS")
		)
		(fp_line
			(start 0.7874 0.4064)
			(end -0.7874 0.4064)
			(stroke
				(width 0.1524)
				(type default)
			)
			(layer "F.SilkS")
		)
		(fp_line
			(start -0.7874 0.4064)
			(end -0.7874 -0.4064)
			(stroke
				(width 0.1524)
				(type default)
			)
			(layer "F.SilkS")
		)
		(fp_line
			(start -0.12065 -0.305054)
			(end -0.12065 -0.2794)
			(stroke
				(width 0.1)
				(type default)
			)
			(layer "F.Fab")
		)
		(fp_line
			(start -0.67945 -0.305054)
			(end -0.12065 -0.305054)
			(stroke
				(width 0.1)
				(type default)
			)
			(layer "F.Fab")
		)
		(fp_line
			(start 0.67945 -0.3048)
			(end 0.67945 0.3048)
			(stroke
				(width 0.1)
				(type default)
			)
			(layer "F.Fab")
		)
		(fp_line
			(start 0.12065 -0.3048)
			(end 0.67945 -0.3048)
			(stroke
				(width 0.1)
				(type default)
			)
			(layer "F.Fab")
		)
		(fp_line
			(start 0.12065 -0.2794)
			(end 0.12065 -0.3048)
			(stroke
				(width 0.1)
				(type default)
			)
			(layer "F.Fab")
		)
		(fp_line
			(start -0.12065 -0.2794)
			(end 0.12065 -0.2794)
			(stroke
				(width 0.1)
				(type default)
			)
			(layer "F.Fab")
		)
		(fp_line
			(start 0.120396 0.2794)
			(end -0.12065 0.2794)
			(stroke
				(width 0.1)
				(type default)
			)
			(layer "F.Fab")
		)
		(fp_line
			(start -0.12065 0.2794)
			(end -0.12065 0.3048)
			(stroke
				(width 0.1)
				(type default)
			)
			(layer "F.Fab")
		)
		(fp_line
			(start 0.67945 0.3048)
			(end 0.120396 0.3048)
			(stroke
				(width 0.1)
				(type default)
			)
			(layer "F.Fab")
		)
		(fp_line
			(start 0.120396 0.3048)
			(end 0.120396 0.2794)
			(stroke
				(width 0.1)
				(type default)
			)
			(layer "F.Fab")
		)
		(fp_line
			(start -0.12065 0.3048)
			(end -0.67945 0.3048)
			(stroke
				(width 0.1)
				(type default)
			)
			(layer "F.Fab")
		)
		(fp_line
			(start -0.67945 0.3048)
			(end -0.67945 -0.305054)
			(stroke
				(width 0.1)
				(type default)
			)
			(layer "F.Fab")
		)
		(pad "1" smd circle
			(at -0.40005 0 90)
			(size 0 0)
			(layers "F.Cu" "F.Mask" "F.Paste")
			(net "P3V3_AUX")
		)
		(pad "2" smd circle
			(at 0.40005 0 90)
			(size 0 0)
			(layers "F.Cu" "F.Mask" "F.Paste")
			(net "MAX31790_U317_ADD0")
		)
	)
	(footprint ""
		(layer "F.Cu")
		(at 6.477 -170.815)
		(property "Reference" "R4856"
			(at 0 0 0)
			(layer "F.SilkS")
			(hide yes)
			(effects
				(font
					(size 1.27 1.27)
				)
			)
		)
		(property "Value" ""
			(at 0 0 0)
			(layer "F.Fab")
			(effects
				(font
					(size 1.27 1.27)
				)
			)
		)
		(duplicate_pad_numbers_are_jumpers no)
		(fp_line
			(start -0.7874 -0.4064)
			(end 0.7874 -0.4064)
			(stroke
				(width 0.1524)
				(type default)
			)
			(layer "F.SilkS")
		)
		(fp_line
			(start -0.7874 0.4064)
			(end -0.7874 -0.4064)
			(stroke
				(width 0.1524)
				(type default)
			)
			(layer "F.SilkS")
		)
		(fp_line
			(start 0.7874 -0.4064)
			(end 0.7874 0.4064)
			(stroke
				(width 0.1524)
				(type default)
			)
			(layer "F.SilkS")
		)
		(fp_line
			(start 0.7874 0.4064)
			(end -0.7874 0.4064)
			(stroke
				(width 0.1524)
				(type default)
			)
			(layer "F.SilkS")
		)
		(fp_line
			(start -0.67945 -0.305054)
			(end -0.12065 -0.305054)
			(stroke
				(width 0.1)
				(type default)
			)
			(layer "F.Fab")
		)
		(fp_line
			(start -0.67945 0.3048)
			(end -0.67945 -0.305054)
			(stroke
				(width 0.1)
				(type default)
			)
			(layer "F.Fab")
		)
		(fp_line
			(start -0.12065 -0.305054)
			(end -0.12065 -0.2794)
			(stroke
				(width 0.1)
				(type default)
			)
			(layer "F.Fab")
		)
		(fp_line
			(start -0.12065 -0.2794)
			(end 0.12065 -0.2794)
			(stroke
				(width 0.1)
				(type default)
			)
			(layer "F.Fab")
		)
		(fp_line
			(start -0.12065 0.2794)
			(end -0.12065 0.3048)
			(stroke
				(width 0.1)
				(type default)
			)
			(layer "F.Fab")
		)
		(fp_line
			(start -0.12065 0.3048)
			(end -0.67945 0.3048)
			(stroke
				(width 0.1)
				(type default)
			)
			(layer "F.Fab")
		)
		(fp_line
			(start 0.120396 0.2794)
			(end -0.12065 0.2794)
			(stroke
				(width 0.1)
				(type default)
			)
			(layer "F.Fab")
		)
		(fp_line
			(start 0.120396 0.3048)
			(end 0.120396 0.2794)
			(stroke
				(width 0.1)
				(type default)
			)
			(layer "F.Fab")
		)
		(fp_line
			(start 0.12065 -0.3048)
			(end 0.67945 -0.3048)
			(stroke
				(width 0.1)
				(type default)
			)
			(layer "F.Fab")
		)
		(fp_line
			(start 0.12065 -0.2794)
			(end 0.12065 -0.3048)
			(stroke
				(width 0.1)
				(type default)
			)
			(layer "F.Fab")
		)
		(fp_line
			(start 0.67945 -0.3048)
			(end 0.67945 0.3048)
			(stroke
				(width 0.1)
				(type default)
			)
			(layer "F.Fab")
		)
		(fp_line
			(start 0.67945 0.3048)
			(end 0.120396 0.3048)
			(stroke
				(width 0.1)
				(type default)
			)
			(layer "F.Fab")
		)
		(pad "1" smd circle
			(at -0.40005 0)
			(size 0 0)
			(layers "F.Cu" "F.Mask" "F.Paste")
			(net "P3V3_AUX")
		)
		(pad "2" smd circle
			(at 0.40005 0)
			(size 0 0)
			(layers "F.Cu" "F.Mask" "F.Paste")
			(net "FAN_5_PRSNT_BUF_R_N")
		)
	)
	(footprint ""
		(layer "F.Cu")
		(at 8.709914 -252.857)
		(property "Reference" "R5423"
			(at 0 0 0)
			(layer "F.SilkS")
			(hide yes)
			(effects
				(font
					(size 1.27 1.27)
				)
			)
		)
		(property "Value" ""
			(at 0 0 0)
			(layer "F.Fab")
			(effects
				(font
					(size 1.27 1.27)
				)
			)
		)
		(duplicate_pad_numbers_are_jumpers no)
		(fp_line
			(start -0.7874 -0.4064)
			(end 0.7874 -0.4064)
			(stroke
				(width 0.1524)
				(type default)
			)
			(layer "F.SilkS")
		)
		(fp_line
			(start -0.7874 0.4064)
			(end -0.7874 -0.4064)
			(stroke
				(width 0.1524)
				(type default)
			)
			(layer "F.SilkS")
		)
		(fp_line
			(start 0.7874 -0.4064)
			(end 0.7874 0.4064)
			(stroke
				(width 0.1524)
				(type default)
			)
			(layer "F.SilkS")
		)
		(fp_line
			(start 0.7874 0.4064)
			(end -0.7874 0.4064)
			(stroke
				(width 0.1524)
				(type default)
			)
			(layer "F.SilkS")
		)
		(fp_line
			(start -0.67945 -0.305054)
			(end -0.12065 -0.305054)
			(stroke
				(width 0.1)
				(type default)
			)
			(layer "F.Fab")
		)
		(fp_line
			(start -0.67945 0.3048)
			(end -0.67945 -0.305054)
			(stroke
				(width 0.1)
				(type default)
			)
			(layer "F.Fab")
		)
		(fp_line
			(start -0.12065 -0.305054)
			(end -0.12065 -0.2794)
			(stroke
				(width 0.1)
				(type default)
			)
			(layer "F.Fab")
		)
		(fp_line
			(start -0.12065 -0.2794)
			(end 0.12065 -0.2794)
			(stroke
				(width 0.1)
				(type default)
			)
			(layer "F.Fab")
		)
		(fp_line
			(start -0.12065 0.2794)
			(end -0.12065 0.3048)
			(stroke
				(width 0.1)
				(type default)
			)
			(layer "F.Fab")
		)
		(fp_line
			(start -0.12065 0.3048)
			(end -0.67945 0.3048)
			(stroke
				(width 0.1)
				(type default)
			)
			(layer "F.Fab")
		)
		(fp_line
			(start 0.120396 0.2794)
			(end -0.12065 0.2794)
			(stroke
				(width 0.1)
				(type default)
			)
			(layer "F.Fab")
		)
		(fp_line
			(start 0.120396 0.3048)
			(end 0.120396 0.2794)
			(stroke
				(width 0.1)
				(type default)
			)
			(layer "F.Fab")
		)
		(fp_line
			(start 0.12065 -0.3048)
			(end 0.67945 -0.3048)
			(stroke
				(width 0.1)
				(type default)
			)
			(layer "F.Fab")
		)
		(fp_line
			(start 0.12065 -0.2794)
			(end 0.12065 -0.3048)
			(stroke
				(width 0.1)
				(type default)
			)
			(layer "F.Fab")
		)
		(fp_line
			(start 0.67945 -0.3048)
			(end 0.67945 0.3048)
			(stroke
				(width 0.1)
				(type default)
			)
			(layer "F.Fab")
		)
		(fp_line
			(start 0.67945 0.3048)
			(end 0.120396 0.3048)
			(stroke
				(width 0.1)
				(type default)
			)
			(layer "F.Fab")
		)
		(pad "1" smd circle
			(at -0.40005 0)
			(size 0 0)
			(layers "F.Cu" "F.Mask" "F.Paste")
			(net "FAN_6_ON")
		)
		(pad "2" smd circle
			(at 0.40005 0)
			(size 0 0)
			(layers "F.Cu" "F.Mask" "F.Paste")
			(net "P52V_FAN_6_EN")
		)
	)
	(footprint ""
		(layer "F.Cu")
		(at 6.858 -135.255 -90)
		(property "Reference" "R5565"
			(at 0 0 270)
			(layer "F.SilkS")
			(hide yes)
			(effects
				(font
					(size 1.27 1.27)
				)
			)
		)
		(property "Value" ""
			(at 0 0 270)
			(layer "F.Fab")
			(effects
				(font
					(size 1.27 1.27)
				)
			)
		)
		(duplicate_pad_numbers_are_jumpers no)
		(fp_line
			(start -0.7874 0.4064)
			(end -0.7874 -0.4064)
			(stroke
				(width 0.1524)
				(type default)
			)
			(layer "F.SilkS")
		)
		(fp_line
			(start 0.7874 0.4064)
			(end -0.7874 0.4064)
			(stroke
				(width 0.1524)
				(type default)
			)
			(layer "F.SilkS")
		)
		(fp_line
			(start -0.7874 -0.4064)
			(end 0.7874 -0.4064)
			(stroke
				(width 0.1524)
				(type default)
			)
			(layer "F.SilkS")
		)
		(fp_line
			(start 0.7874 -0.4064)
			(end 0.7874 0.4064)
			(stroke
				(width 0.1524)
				(type default)
			)
			(layer "F.SilkS")
		)
		(fp_line
			(start -0.67945 0.3048)
			(end -0.67945 -0.305054)
			(stroke
				(width 0.1)
				(type default)
			)
			(layer "F.Fab")
		)
		(fp_line
			(start -0.12065 0.3048)
			(end -0.67945 0.3048)
			(stroke
				(width 0.1)
				(type default)
			)
			(layer "F.Fab")
		)
		(fp_line
			(start 0.120396 0.3048)
			(end 0.120396 0.2794)
			(stroke
				(width 0.1)
				(type default)
			)
			(layer "F.Fab")
		)
		(fp_line
			(start 0.67945 0.3048)
			(end 0.120396 0.3048)
			(stroke
				(width 0.1)
				(type default)
			)
			(layer "F.Fab")
		)
		(fp_line
			(start -0.12065 0.2794)
			(end -0.12065 0.3048)
			(stroke
				(width 0.1)
				(type default)
			)
			(layer "F.Fab")
		)
		(fp_line
			(start 0.120396 0.2794)
			(end -0.12065 0.2794)
			(stroke
				(width 0.1)
				(type default)
			)
			(layer "F.Fab")
		)
		(fp_line
			(start -0.12065 -0.2794)
			(end 0.12065 -0.2794)
			(stroke
				(width 0.1)
				(type default)
			)
			(layer "F.Fab")
		)
		(fp_line
			(start 0.12065 -0.2794)
			(end 0.12065 -0.3048)
			(stroke
				(width 0.1)
				(type default)
			)
			(layer "F.Fab")
		)
		(fp_line
			(start 0.12065 -0.3048)
			(end 0.67945 -0.3048)
			(stroke
				(width 0.1)
				(type default)
			)
			(layer "F.Fab")
		)
		(fp_line
			(start 0.67945 -0.3048)
			(end 0.67945 0.3048)
			(stroke
				(width 0.1)
				(type default)
			)
			(layer "F.Fab")
		)
		(fp_line
			(start -0.67945 -0.305054)
			(end -0.12065 -0.305054)
			(stroke
				(width 0.1)
				(type default)
			)
			(layer "F.Fab")
		)
		(fp_line
			(start -0.12065 -0.305054)
			(end -0.12065 -0.2794)
			(stroke
				(width 0.1)
				(type default)
			)
			(layer "F.Fab")
		)
		(pad "1" smd circle
			(at -0.40005 0 270)
			(size 0 0)
			(layers "F.Cu" "F.Mask" "F.Paste")
			(net "P3V3_AUX")
		)
		(pad "2" smd circle
			(at 0.40005 0 270)
			(size 0 0)
			(layers "F.Cu" "F.Mask" "F.Paste")
			(net "U404_ADD0")
		)
	)
	(footprint ""
		(layer "F.Cu")
		(at 14.351 -208.435956 180)
		(property "Reference" "D252"
			(at 4.064 -1.071626 0)
			(unlocked yes)
			(layer "F.SilkS")
			(effects
				(font
					(size 0.7874 0.5842)
					(thickness 0.1524)
				)
				(justify left)
			)
		)
		(property "Value" ""
			(at 0 0 180)
			(layer "F.Fab")
			(effects
				(font
					(size 1.27 1.27)
				)
			)
		)
		(duplicate_pad_numbers_are_jumpers no)
		(fp_line
			(start 0.94488 0.450088)
			(end 0.94488 -0.450088)
			(stroke
				(width 0.1524)
				(type default)
			)
			(layer "F.SilkS")
		)
		(fp_line
			(start 0.94488 -0.450088)
			(end -0.854964 -0.450088)
			(stroke
				(width 0.1524)
				(type default)
			)
			(layer "F.SilkS")
		)
		(fp_line
			(start 0.870458 -0.2794)
			(end 0.845058 0.4064)
			(stroke
				(width 0.1524)
				(type default)
			)
			(layer "F.SilkS")
		)
		(fp_line
			(start 0.845058 0.4064)
			(end 0.845058 -0.381)
			(stroke
				(width 0.1524)
				(type default)
			)
			(layer "F.SilkS")
		)
		(fp_line
			(start -0.854964 0.450088)
			(end 0.925068 0.450088)
			(stroke
				(width 0.1524)
				(type default)
			)
			(layer "F.SilkS")
		)
		(fp_line
			(start -0.854964 -0.450088)
			(end -0.854964 0.450088)
			(stroke
				(width 0.1524)
				(type default)
			)
			(layer "F.SilkS")
		)
		(fp_line
			(start 0.54991 0.350012)
			(end 0.54991 -0.350012)
			(stroke
				(width 0.1)
				(type default)
			)
			(layer "F.Fab")
		)
		(fp_line
			(start 0.54991 -0.350012)
			(end -0.54991 -0.350012)
			(stroke
				(width 0.1)
				(type default)
			)
			(layer "F.Fab")
		)
		(fp_line
			(start -0.54991 0.350012)
			(end 0.54991 0.350012)
			(stroke
				(width 0.1)
				(type default)
			)
			(layer "F.Fab")
		)
		(fp_line
			(start -0.54991 -0.350012)
			(end -0.54991 0.350012)
			(stroke
				(width 0.1)
				(type default)
			)
			(layer "F.Fab")
		)
		(fp_text user "-"
			(at 2.159 0.193294 0)
			(unlocked yes)
			(layer "F.SilkS")
			(effects
				(font
					(size 1.905 1.4224)
					(thickness 0.1524)
				)
				(justify left)
			)
		)
		(fp_text user "+"
			(at -2.38125 0.987044 270)
			(unlocked yes)
			(layer "F.SilkS")
			(effects
				(font
					(size 1.905 1.4224)
					(thickness 0.1524)
				)
				(justify left)
			)
		)
		(fp_text user "-"
			(at 2.48539 0.239014 0)
			(unlocked yes)
			(layer "F.Fab")
			(effects
				(font
					(size 1.905 1.4224)
					(thickness 0.1524)
				)
				(justify left)
			)
		)
		(fp_text user "+"
			(at -0.808228 0.239014 0)
			(unlocked yes)
			(layer "F.Fab")
			(effects
				(font
					(size 1.905 1.4224)
					(thickness 0.1524)
				)
				(justify left)
			)
		)
		(pad "A" smd rect
			(at -0.424942 0 180)
			(size 0.5588 0.6096)
			(layers "F.Cu" "F.Mask" "F.Paste")
			(net "GND")
		)
		(pad "C" smd rect
			(at 0.424942 0)
			(size 0.5588 0.6096)
			(layers "F.Cu" "F.Mask" "F.Paste")
			(net "FAN_6_OK_R_LED_N")
		)
	)
	(footprint ""
		(layer "F.Cu")
		(at 2.6924 -219.583 -90)
		(property "Reference" "C2039"
			(at 0 0 270)
			(layer "F.SilkS")
			(hide yes)
			(effects
				(font
					(size 1.27 1.27)
				)
			)
		)
		(property "Value" ""
			(at 0 0 270)
			(layer "F.Fab")
			(effects
				(font
					(size 1.27 1.27)
				)
			)
		)
		(duplicate_pad_numbers_are_jumpers no)
		(fp_line
			(start -0.7874 0.4064)
			(end -0.7874 -0.4064)
			(stroke
				(width 0.1524)
				(type default)
			)
			(layer "F.SilkS")
		)
		(fp_line
			(start 0.7874 0.4064)
			(end -0.7874 0.4064)
			(stroke
				(width 0.1524)
				(type default)
			)
			(layer "F.SilkS")
		)
		(fp_line
			(start -0.7874 -0.4064)
			(end 0.7874 -0.4064)
			(stroke
				(width 0.1524)
				(type default)
			)
			(layer "F.SilkS")
		)
		(fp_line
			(start 0.7874 -0.4064)
			(end 0.7874 0.4064)
			(stroke
				(width 0.1524)
				(type default)
			)
			(layer "F.SilkS")
		)
		(fp_line
			(start -0.6858 0.3048)
			(end -0.6858 -0.3048)
			(stroke
				(width 0.1)
				(type default)
			)
			(layer "F.Fab")
		)
		(fp_line
			(start -0.1016 0.3048)
			(end -0.6858 0.3048)
			(stroke
				(width 0.1)
				(type default)
			)
			(layer "F.Fab")
		)
		(fp_line
			(start 0.1016 0.3048)
			(end 0.1016 0.2794)
			(stroke
				(width 0.1)
				(type default)
			)
			(layer "F.Fab")
		)
		(fp_line
			(start 0.6858 0.3048)
			(end 0.1016 0.3048)
			(stroke
				(width 0.1)
				(type default)
			)
			(layer "F.Fab")
		)
		(fp_line
			(start -0.1016 0.2794)
			(end -0.1016 0.3048)
			(stroke
				(width 0.1)
				(type default)
			)
			(layer "F.Fab")
		)
		(fp_line
			(start 0.1016 0.2794)
			(end -0.1016 0.2794)
			(stroke
				(width 0.1)
				(type default)
			)
			(layer "F.Fab")
		)
		(fp_line
			(start -0.1016 -0.2794)
			(end 0.1016 -0.2794)
			(stroke
				(width 0.1)
				(type default)
			)
			(layer "F.Fab")
		)
		(fp_line
			(start 0.1016 -0.2794)
			(end 0.1016 -0.3048)
			(stroke
				(width 0.1)
				(type default)
			)
			(layer "F.Fab")
		)
		(fp_line
			(start -0.6858 -0.3048)
			(end -0.1016 -0.3048)
			(stroke
				(width 0.1)
				(type default)
			)
			(layer "F.Fab")
		)
		(fp_line
			(start -0.1016 -0.3048)
			(end -0.1016 -0.2794)
			(stroke
				(width 0.1)
				(type default)
			)
			(layer "F.Fab")
		)
		(fp_line
			(start 0.1016 -0.3048)
			(end 0.6858 -0.3048)
			(stroke
				(width 0.1)
				(type default)
			)
			(layer "F.Fab")
		)
		(fp_line
			(start 0.6858 -0.3048)
			(end 0.6858 0.3048)
			(stroke
				(width 0.1)
				(type default)
			)
			(layer "F.Fab")
		)
		(pad "1" smd rect
			(at -0.40005 0 90)
			(size 0.4572 0.508)
			(layers "F.Cu" "F.Mask" "F.Paste")
			(net "GND")
		)
		(pad "2" smd rect
			(at 0.40005 0 90)
			(size 0.4572 0.508)
			(layers "F.Cu" "F.Mask" "F.Paste")
			(net "P12V_LED_FAN6")
		)
	)
)
